(kicad_pcb
	(version 20221018)
	(generator pcbnew)
	(general
    (thickness 1.586)
  )
	(paper "A4")
	(title_block
    (date "2024-03-26")
    (rev "1.1.3")
		(comment 9 "footprint 114 of 146 (J10), pads 1-68 of 68")
	)
	(layers
    (0 "F.Cu" signal)
    (1 "In1.Cu" power)
    (2 "In2.Cu" power)
    (31 "B.Cu" signal)
    (32 "B.Adhes" user "B.Adhesive")
    (33 "F.Adhes" user "F.Adhesive")
    (34 "B.Paste" user)
    (35 "F.Paste" user)
    (36 "B.SilkS" user "B.Silkscreen")
    (37 "F.SilkS" user "F.Silkscreen")
    (38 "B.Mask" user)
    (39 "F.Mask" user)
    (40 "Dwgs.User" user "User.Drawings")
    (41 "Cmts.User" user "User.Comments")
    (42 "Eco1.User" user "User.Eco1")
    (43 "Eco2.User" user "User.Eco2")
    (44 "Edge.Cuts" user)
    (45 "Margin" user)
    (46 "B.CrtYd" user "B.Courtyard")
    (47 "F.CrtYd" user "F.Courtyard")
    (48 "B.Fab" user)
    (49 "F.Fab" user)
  )
	(footprint "scalenode-cm4-baseboard-footprints:Conn_Hermaphroditic_Samtec_LSHM_2x30_LSHM-130-01-XXX-RH-A-S-K-XX" locked
    (layer "B.Cu")
    (at 199.181 76.7 -90)
    (property "Author" "Antmicro")
    (property "License" "Apache-2.0")
    (property "MPN" "LSHM-130-01-L-RH-A-S-K-TR")
    (property "Manufacturer" "Samtec")
    (property "Sheetfile" "expansion-connectors.kicad_sch")
    (property "Sheetname" "Expansion connectors")
    (attr smd)
    (fp_text reference "J10" (at -6.9 2.011 90) (layer "B.SilkS")
        (effects (font (size 0.7 0.7) (thickness 0.15)) (justify left bottom mirror))
    )
    (fp_text value "Hermaphroditic_Samtec_LSHM_2x30_LSHM-130-01-L-RH-A-S-K-TR" (at 18.35 -0.519 180) (layer "B.Fab")
        (effects (font (size 0.7 0.7) (thickness 0.15)) (justify left bottom mirror))
    )
    (pad "" np_thru_hole circle locked (at -9.25 0 270) (size 1.45 1.45) (drill 1.45) (layers "*.Cu" "*.Mask"))
    (pad "" np_thru_hole circle locked (at 9.249 0 270) (size 1.45 1.45) (drill 1.45) (layers "*.Cu" "*.Mask"))
    (pad "01" smd rect locked (at -7.25 0.6 270) (size 0.3 1.8) (layers "B.Cu" "B.Paste" "B.Mask")
      (net 12 "VCC5V0") (pinfunction "01") (pintype "passive"))
    (pad "02" smd rect locked (at -7.25 -2.064 270) (size 0.3 1.63) (layers "B.Cu" "B.Paste" "B.Mask")
      (net 253 "3V3_OUT") (pinfunction "02") (pintype "passive"))
    (pad "03" smd rect locked (at -6.75 0.6 270) (size 0.3 1.8) (layers "B.Cu" "B.Paste" "B.Mask")
      (net 12 "VCC5V0") (pinfunction "03") (pintype "passive"))
    (pad "04" smd rect locked (at -6.75 -2.064 270) (size 0.3 1.63) (layers "B.Cu" "B.Paste" "B.Mask")
      (net 253 "3V3_OUT") (pinfunction "04") (pintype "passive"))
    (pad "05" smd rect locked (at -6.25 0.6 270) (size 0.3 1.8) (layers "B.Cu" "B.Paste" "B.Mask")
      (net 12 "VCC5V0") (pinfunction "05") (pintype "passive"))
    (pad "06" smd rect locked (at -6.25 -2.064 270) (size 0.3 1.63) (layers "B.Cu" "B.Paste" "B.Mask")
      (net 253 "3V3_OUT") (pinfunction "06") (pintype "passive"))
    (pad "07" smd rect locked (at -5.75 0.6 270) (size 0.3 1.8) (layers "B.Cu" "B.Paste" "B.Mask")
      (net 12 "VCC5V0") (pinfunction "07") (pintype "passive"))
    (pad "08" smd rect locked (at -5.75 -2.064 270) (size 0.3 1.63) (layers "B.Cu" "B.Paste" "B.Mask")
      (net 253 "3V3_OUT") (pinfunction "08") (pintype "passive"))
    (pad "09" smd rect locked (at -5.25 0.6 270) (size 0.3 1.8) (layers "B.Cu" "B.Paste" "B.Mask")
      (net 12 "VCC5V0") (pinfunction "09") (pintype "passive"))
    (pad "10" smd rect locked (at -5.25 -2.064 270) (size 0.3 1.63) (layers "B.Cu" "B.Paste" "B.Mask")
      (net 253 "3V3_OUT") (pinfunction "10") (pintype "passive"))
    (pad "11" smd rect locked (at -4.75 0.6 270) (size 0.3 1.8) (layers "B.Cu" "B.Paste" "B.Mask")
      (net 12 "VCC5V0") (pinfunction "11") (pintype "passive"))
    (pad "12" smd rect locked (at -4.75 -2.064 270) (size 0.3 1.63) (layers "B.Cu" "B.Paste" "B.Mask")
      (net 253 "3V3_OUT") (pinfunction "12") (pintype "passive"))
    (pad "13" smd rect locked (at -4.25 0.6 270) (size 0.3 1.8) (layers "B.Cu" "B.Paste" "B.Mask")
      (net 211 "unconnected-(J10-Pad13)") (pinfunction "13") (pintype "passive+no_connect"))
    (pad "14" smd rect locked (at -4.25 -2.064 270) (size 0.3 1.63) (layers "B.Cu" "B.Paste" "B.Mask")
      (net 212 "unconnected-(J10-Pad14)") (pinfunction "14") (pintype "passive+no_connect"))
    (pad "15" smd rect locked (at -3.75 0.6 270) (size 0.3 1.8) (layers "B.Cu" "B.Paste" "B.Mask")
      (net 213 "unconnected-(J10-Pad15)") (pinfunction "15") (pintype "passive+no_connect"))
    (pad "16" smd rect locked (at -3.75 -2.064 270) (size 0.3 1.63) (layers "B.Cu" "B.Paste" "B.Mask")
      (net 214 "unconnected-(J10-Pad16)") (pinfunction "16") (pintype "passive+no_connect"))
    (pad "17" smd rect locked (at -3.25 0.6 270) (size 0.3 1.8) (layers "B.Cu" "B.Paste" "B.Mask")
      (net 11 "GND") (pinfunction "17") (pintype "passive"))
    (pad "18" smd rect locked (at -3.25 -2.064 270) (size 0.3 1.63) (layers "B.Cu" "B.Paste" "B.Mask")
      (net 11 "GND") (pinfunction "18") (pintype "passive"))
    (pad "19" smd rect locked (at -2.75 0.6 270) (size 0.3 1.8) (layers "B.Cu" "B.Paste" "B.Mask")
      (net 11 "GND") (pinfunction "19") (pintype "passive"))
    (pad "20" smd rect locked (at -2.75 -2.064 270) (size 0.3 1.63) (layers "B.Cu" "B.Paste" "B.Mask")
      (net 11 "GND") (pinfunction "20") (pintype "passive"))
    (pad "21" smd rect locked (at -2.25 0.6 270) (size 0.3 1.8) (layers "B.Cu" "B.Paste" "B.Mask")
      (net 11 "GND") (pinfunction "21") (pintype "passive"))
    (pad "22" smd rect locked (at -2.25 -2.064 270) (size 0.3 1.63) (layers "B.Cu" "B.Paste" "B.Mask")
      (net 11 "GND") (pinfunction "22") (pintype "passive"))
    (pad "23" smd rect locked (at -1.75 0.6 270) (size 0.3 1.8) (layers "B.Cu" "B.Paste" "B.Mask")
      (net 11 "GND") (pinfunction "23") (pintype "passive"))
    (pad "24" smd rect locked (at -1.75 -2.064 270) (size 0.3 1.63) (layers "B.Cu" "B.Paste" "B.Mask")
      (net 11 "GND") (pinfunction "24") (pintype "passive"))
    (pad "25" smd rect locked (at -1.25 0.6 270) (size 0.3 1.8) (layers "B.Cu" "B.Paste" "B.Mask")
      (net 11 "GND") (pinfunction "25") (pintype "passive"))
    (pad "26" smd rect locked (at -1.25 -2.064 270) (size 0.3 1.63) (layers "B.Cu" "B.Paste" "B.Mask")
      (net 11 "GND") (pinfunction "26") (pintype "passive"))
    (pad "27" smd rect locked (at -0.75 0.6 270) (size 0.3 1.8) (layers "B.Cu" "B.Paste" "B.Mask")
      (net 152 "HDMI0_SCL") (pinfunction "27") (pintype "passive"))
    (pad "28" smd rect locked (at -0.75 -2.064 270) (size 0.3 1.63) (layers "B.Cu" "B.Paste" "B.Mask")
      (net 237 "Adapter_RXD") (pinfunction "28") (pintype "passive"))
    (pad "29" smd rect locked (at -0.25 0.6 270) (size 0.3 1.8) (layers "B.Cu" "B.Paste" "B.Mask")
      (net 151 "HDMI0_SDA") (pinfunction "29") (pintype "passive"))
    (pad "30" smd rect locked (at -0.25 -2.064 270) (size 0.3 1.63) (layers "B.Cu" "B.Paste" "B.Mask")
      (net 238 "Adapter_TXD") (pinfunction "30") (pintype "passive"))
    (pad "31" smd rect locked (at 0.249 0.6 270) (size 0.3 1.8) (layers "B.Cu" "B.Paste" "B.Mask")
      (net 125 "HDMI0_CEC") (pinfunction "31") (pintype "passive"))
    (pad "32" smd rect locked (at 0.249 -2.064 270) (size 0.3 1.63) (layers "B.Cu" "B.Paste" "B.Mask")
      (net 11 "GND") (pinfunction "32") (pintype "passive"))
    (pad "33" smd rect locked (at 0.749 0.6 270) (size 0.3 1.8) (layers "B.Cu" "B.Paste" "B.Mask")
      (net 127 "HDMI0_HOTPLUG") (pinfunction "33") (pintype "passive"))
    (pad "34" smd rect locked (at 0.749 -2.064 270) (size 0.3 1.63) (layers "B.Cu" "B.Paste" "B.Mask")
      (net 240 "Adapter_USB_N") (pinfunction "34") (pintype "passive"))
    (pad "35" smd rect locked (at 1.249 0.6 270) (size 0.3 1.8) (layers "B.Cu" "B.Paste" "B.Mask")
      (net 11 "GND") (pinfunction "35") (pintype "passive"))
    (pad "36" smd rect locked (at 1.249 -2.064 270) (size 0.3 1.63) (layers "B.Cu" "B.Paste" "B.Mask")
      (net 239 "Adapter_USB_P") (pinfunction "36") (pintype "passive"))
    (pad "37" smd rect locked (at 1.749 0.6 270) (size 0.3 1.8) (layers "B.Cu" "B.Paste" "B.Mask")
      (net 36 "HDMI0_D2_P") (pinfunction "37") (pintype "passive"))
    (pad "38" smd rect locked (at 1.749 -2.064 270) (size 0.3 1.63) (layers "B.Cu" "B.Paste" "B.Mask")
      (net 11 "GND") (pinfunction "38") (pintype "passive"))
    (pad "39" smd rect locked (at 2.249 0.6 270) (size 0.3 1.8) (layers "B.Cu" "B.Paste" "B.Mask")
      (net 37 "HDMI0_D2_N") (pinfunction "39") (pintype "passive"))
    (pad "40" smd rect locked (at 2.249 -2.064 270) (size 0.3 1.63) (layers "B.Cu" "B.Paste" "B.Mask")
      (net 53 "SCL0") (pinfunction "40") (pintype "passive"))
    (pad "41" smd rect locked (at 2.749 0.6 270) (size 0.3 1.8) (layers "B.Cu" "B.Paste" "B.Mask")
      (net 11 "GND") (pinfunction "41") (pintype "passive"))
    (pad "42" smd rect locked (at 2.749 -2.064 270) (size 0.3 1.63) (layers "B.Cu" "B.Paste" "B.Mask")
      (net 52 "SDA0") (pinfunction "42") (pintype "passive"))
    (pad "43" smd rect locked (at 3.249 0.6 270) (size 0.3 1.8) (layers "B.Cu" "B.Paste" "B.Mask")
      (net 38 "HDMI0_D1_P") (pinfunction "43") (pintype "passive"))
    (pad "44" smd rect locked (at 3.249 -2.064 270) (size 0.3 1.63) (layers "B.Cu" "B.Paste" "B.Mask")
      (net 11 "GND") (pinfunction "44") (pintype "passive"))
    (pad "45" smd rect locked (at 3.749 0.6 270) (size 0.3 1.8) (layers "B.Cu" "B.Paste" "B.Mask")
      (net 39 "HDMI0_D1_N") (pinfunction "45") (pintype "passive"))
    (pad "46" smd rect locked (at 3.749 -2.064 270) (size 0.3 1.63) (layers "B.Cu" "B.Paste" "B.Mask")
      (net 80 "GPIO26") (pinfunction "46") (pintype "passive"))
    (pad "47" smd rect locked (at 4.249 0.6 270) (size 0.3 1.8) (layers "B.Cu" "B.Paste" "B.Mask")
      (net 11 "GND") (pinfunction "47") (pintype "passive"))
    (pad "48" smd rect locked (at 4.249 -2.064 270) (size 0.3 1.63) (layers "B.Cu" "B.Paste" "B.Mask")
      (net 61 "GPIO18") (pinfunction "48") (pintype "passive"))
    (pad "49" smd rect locked (at 4.749 0.6 270) (size 0.3 1.8) (layers "B.Cu" "B.Paste" "B.Mask")
      (net 142 "HDMI0_D0_P") (pinfunction "49") (pintype "passive"))
    (pad "50" smd rect locked (at 4.749 -2.064 270) (size 0.3 1.63) (layers "B.Cu" "B.Paste" "B.Mask")
      (net 11 "GND") (pinfunction "50") (pintype "passive"))
    (pad "51" smd rect locked (at 5.249 0.6 270) (size 0.3 1.8) (layers "B.Cu" "B.Paste" "B.Mask")
      (net 144 "HDMI0_D0_N") (pinfunction "51") (pintype "passive"))
    (pad "52" smd rect locked (at 5.249 -2.064 270) (size 0.3 1.63) (layers "B.Cu" "B.Paste" "B.Mask")
      (net 71 "GPIO7") (pinfunction "52") (pintype "passive"))
    (pad "53" smd rect locked (at 5.749 0.6 270) (size 0.3 1.8) (layers "B.Cu" "B.Paste" "B.Mask")
      (net 11 "GND") (pinfunction "53") (pintype "passive"))
    (pad "54" smd rect locked (at 5.749 -2.064 270) (size 0.3 1.63) (layers "B.Cu" "B.Paste" "B.Mask")
      (net 69 "GPIO8") (pinfunction "54") (pintype "passive"))
    (pad "55" smd rect locked (at 6.249 0.6 270) (size 0.3 1.8) (layers "B.Cu" "B.Paste" "B.Mask")
      (net 40 "HDMI0_CK_P") (pinfunction "55") (pintype "passive"))
    (pad "56" smd rect locked (at 6.249 -2.064 270) (size 0.3 1.63) (layers "B.Cu" "B.Paste" "B.Mask")
      (net 11 "GND") (pinfunction "56") (pintype "passive"))
    (pad "57" smd rect locked (at 6.749 0.6 270) (size 0.3 1.8) (layers "B.Cu" "B.Paste" "B.Mask")
      (net 41 "HDMI0_CK_N") (pinfunction "57") (pintype "passive"))
    (pad "58" smd rect locked (at 6.749 -2.064 270) (size 0.3 1.63) (layers "B.Cu" "B.Paste" "B.Mask")
      (net 65 "GPIO24") (pinfunction "58") (pintype "passive"))
    (pad "59" smd rect locked (at 7.249 0.6 270) (size 0.3 1.8) (layers "B.Cu" "B.Paste" "B.Mask")
      (net 11 "GND") (pinfunction "59") (pintype "passive"))
    (pad "60" smd rect locked (at 7.249 -2.064 270) (size 0.3 1.63) (layers "B.Cu" "B.Paste" "B.Mask")
      (net 67 "GPIO25") (pinfunction "60") (pintype "passive"))
    (pad "S1" thru_hole circle locked (at -8.825 -1.679 270) (size 1.208 1.208) (drill 0.7) (layers "*.Cu" "*.Mask")
      (net 11 "GND") (pinfunction "SHIELD") (pintype "passive"))
    (pad "S2" thru_hole circle locked (at 8.824 -1.679 270) (size 1.208 1.208) (drill 0.7) (layers "*.Cu" "*.Mask")
      (net 11 "GND") (pinfunction "SHIELD") (pintype "passive"))
    (pad "WT1" thru_hole circle locked (at -10.801 -0.55 270) (size 1.208 1.208) (drill 0.7) (layers "*.Cu" "*.Mask"))
    (pad "WT2" thru_hole circle locked (at -10.801 -2.799 270) (size 1.208 1.208) (drill 0.7) (layers "*.Cu" "*.Mask"))
    (pad "WT3" thru_hole circle locked (at 10.8 -0.55 270) (size 1.208 1.208) (drill 0.7) (layers "*.Cu" "*.Mask"))
    (pad "WT4" thru_hole circle locked (at 10.8 -2.799 270) (size 1.208 1.208) (drill 0.7) (layers "*.Cu" "*.Mask"))
  )
)
